# BASEBOARD_FAB2 (Tioga Pass) — schematic netlist excerpt (pin names and nets, part order shuffled) for the footprints in the layout excerpt that follows; sources: Cadence DE-HDL packaged netlist, KiCad conversion of Wiwynn_Tioga_Pass_MB.brd

C7A31  CAP  47UF 4V 20% X6S  pkg 0805  page 132 : A = PVNN_PCH_STBY ; B = GND
C7A27  CAPP  470UF 2V 20% ALUM  pkg SM  page 236 : A = PVNN_PCH_STBY ; B = GND
C1C5  CAP  1.0UF 16V 10% X6S  pkg 0402  page 210 : A = VR_PVSA_CPU1_VCIN ; B = GND

(kicad_pcb
	(version 20260206)
	(generator "pcbnew")
	(generator_version "10.0")
	(general
		(thickness 1.6)
		(legacy_teardrops no)
	)
	(paper "A4")
	(title_block
		(title "Wiwynn_Tioga_Pass_MB.brd")
		(comment 1 "Tioga Pass / footprints 2127-2129 of 4770")
	)
	(layers
		(0 "F.Cu" signal "TOP")
		(4 "In1.Cu" signal "L2GND")
		(6 "In2.Cu" signal "L3")
		(8 "In3.Cu" signal "L4GND")
		(10 "In4.Cu" signal "L5")
		(12 "In5.Cu" signal "L6GND")
		(14 "In6.Cu" signal "L7VCC")
		(16 "In7.Cu" signal "L8VCC")
		(18 "In8.Cu" signal "L9GND")
		(20 "In9.Cu" signal "L10")
		(22 "In10.Cu" signal "L11GND")
		(24 "In11.Cu" signal "L12")
		(26 "In12.Cu" signal "L13GND")
		(2 "B.Cu" signal "BOTTOM")
		(9 "F.Adhes" user "F.Adhesive")
		(11 "B.Adhes" user "B.Adhesive")
		(13 "F.Paste" user "Package Geometry/Pastemask Top")
		(15 "B.Paste" user "Package Geometry/Pastemask Bottom")
		(5 "F.SilkS" user "Ref Des/Silkscreen Top")
		(7 "B.SilkS" user "Ref Des/Silkscreen Bottom")
		(1 "F.Mask" user "Board Geometry/Soldermask Top")
		(3 "B.Mask" user "Board Geometry/Soldermask Bottom")
		(17 "Dwgs.User" user "User.Drawings")
		(19 "Cmts.User" user "User.Comments")
		(21 "Eco1.User" user "User.Eco1")
		(23 "Eco2.User" user "User.Eco2")
		(25 "Edge.Cuts" user "Board Geometry/Outline")
		(27 "Margin" user)
		(31 "F.CrtYd" user "Package Geometry/Place Bound Top")
		(29 "B.CrtYd" user "Package Geometry/Place Bound Bottom")
		(35 "F.Fab" user "Ref Des/Assembly Top")
		(33 "B.Fab" user "Ref Des/Assembly Bottom")
	)
	(footprint ""
		(layer "F.Cu")
		(at 32.352234 -93.625162 -90)
		(property "Reference" "C1C5"
			(at 0 0 270)
			(layer "F.SilkS")
			(hide yes)
			(effects
				(font
					(size 1.27 1.27)
				)
			)
		)
		(property "Value" ""
			(at 0 0 270)
			(layer "F.Fab")
			(effects
				(font
					(size 1.27 1.27)
				)
			)
		)
		(duplicate_pad_numbers_are_jumpers no)
		(fp_rect
			(start 0.3048 0.9906)
			(end -0.3048 -0.1016)
			(stroke
				(width 0)
				(type default)
			)
			(fill no)
			(layer "F.CrtYd")
		)
		(fp_line
			(start -0.3048 0.9906)
			(end 0.3048 0.9906)
			(stroke
				(width 0.1)
				(type default)
			)
			(layer "F.Fab")
		)
		(fp_line
			(start 0.3048 0.9906)
			(end 0.3048 -0.1016)
			(stroke
				(width 0.1)
				(type default)
			)
			(layer "F.Fab")
		)
		(fp_line
			(start -0.3048 -0.1016)
			(end -0.3048 0.9906)
			(stroke
				(width 0.1)
				(type default)
			)
			(layer "F.Fab")
		)
		(fp_line
			(start 0.3048 -0.1016)
			(end -0.3048 -0.1016)
			(stroke
				(width 0.1)
				(type default)
			)
			(layer "F.Fab")
		)
		(pad "1" smd rect
			(at 0 0 270)
			(size 0.508 0.508)
			(layers "F.Cu" "F.Mask" "F.Paste")
			(net "VR_PVSA_CPU1_VCIN")
		)
		(pad "2" smd rect
			(at 0 0.889 270)
			(size 0.508 0.508)
			(layers "F.Cu" "F.Mask" "F.Paste")
			(net "GND")
		)
		(zone
			(layer "F.Cu")
			(hatch none 0.5)
			(connect_pads
				(clearance 0)
			)
			(min_thickness 0.25)
			(keepout
				(tracks allowed)
				(vias not_allowed)
				(pads allowed)
				(copperpour not_allowed)
				(footprints allowed)
			)
			(placement
				(enabled no)
				(sheetname "")
			)
			(fill
				(thermal_gap 0.5)
				(thermal_bridge_width 0.5)
				(island_removal_mode 0)
			)
			(polygon
				(pts
					(xy 31.717234 -93.371162) (xy 32.098234 -93.371162) (xy 32.098234 -93.879162) (xy 31.717234 -93.879162)
				)
			)
		)
		(zone
			(layer "F.Cu")
			(hatch none 0.5)
			(connect_pads
				(clearance 0)
			)
			(min_thickness 0.25)
			(keepout
				(tracks not_allowed)
				(vias allowed)
				(pads allowed)
				(copperpour not_allowed)
				(footprints allowed)
			)
			(placement
				(enabled no)
				(sheetname "")
			)
			(fill
				(thermal_gap 0.5)
				(thermal_bridge_width 0.5)
				(island_removal_mode 0)
			)
			(polygon
				(pts
					(xy 31.717234 -93.371162) (xy 32.098234 -93.371162) (xy 32.098234 -93.879162) (xy 31.717234 -93.879162)
				)
			)
		)
	)
	(footprint ""
		(layer "F.Cu")
		(at 381.2159 -137.4648)
		(property "Reference" "C7A31"
			(at 0 0 0)
			(layer "F.SilkS")
			(hide yes)
			(effects
				(font
					(size 1.27 1.27)
				)
			)
		)
		(property "Value" ""
			(at 0 0 0)
			(layer "F.Fab")
			(effects
				(font
					(size 1.27 1.27)
				)
			)
		)
		(duplicate_pad_numbers_are_jumpers no)
		(fp_rect
			(start -0.7239 1.9939)
			(end 0.7239 -0.2159)
			(stroke
				(width 0)
				(type default)
			)
			(fill no)
			(layer "F.CrtYd")
		)
		(fp_line
			(start -0.7239 -0.2159)
			(end -0.7239 1.9939)
			(stroke
				(width 0.1)
				(type default)
			)
			(layer "F.Fab")
		)
		(fp_line
			(start -0.7239 1.9939)
			(end 0.7239 1.9939)
			(stroke
				(width 0.1)
				(type default)
			)
			(layer "F.Fab")
		)
		(fp_line
			(start 0.7239 -0.2159)
			(end -0.7239 -0.2159)
			(stroke
				(width 0.1)
				(type default)
			)
			(layer "F.Fab")
		)
		(fp_line
			(start 0.7239 1.9939)
			(end 0.7239 -0.2159)
			(stroke
				(width 0.1)
				(type default)
			)
			(layer "F.Fab")
		)
		(pad "1" smd rect
			(at 0 0)
			(size 1.27 1.016)
			(layers "F.Cu" "F.Mask" "F.Paste")
			(net "PVNN_PCH_STBY")
		)
		(pad "2" smd rect
			(at 0 1.778)
			(size 1.27 1.016)
			(layers "F.Cu" "F.Mask" "F.Paste")
			(net "GND")
		)
		(zone
			(layer "F.Cu")
			(hatch none 0.5)
			(connect_pads
				(clearance 0)
			)
			(min_thickness 0.25)
			(keepout
				(tracks not_allowed)
				(vias allowed)
				(pads allowed)
				(copperpour not_allowed)
				(footprints allowed)
			)
			(placement
				(enabled no)
				(sheetname "")
			)
			(fill
				(thermal_gap 0.5)
				(thermal_bridge_width 0.5)
				(island_removal_mode 0)
			)
			(polygon
				(pts
					(xy 380.5809 -136.1948) (xy 381.8509 -136.1948) (xy 381.8509 -136.9568) (xy 380.5809 -136.9568)
				)
			)
		)
	)
	(footprint ""
		(layer "F.Cu")
		(at 369.4684 -141.2494 180)
		(property "Reference" "C7A27"
			(at -0.5588 -2.76987 0)
			(unlocked yes)
			(layer "F.SilkS")
			(effects
				(font
					(size 0.7874 0.5842)
					(thickness 0.1524)
				)
			)
		)
		(property "Value" ""
			(at 0 0 180)
			(layer "F.Fab")
			(effects
				(font
					(size 1.27 1.27)
				)
			)
		)
		(duplicate_pad_numbers_are_jumpers no)
		(fp_line
			(start 2.504948 1.633728)
			(end 1.6002 1.633728)
			(stroke
				(width 0.1524)
				(type default)
			)
			(layer "F.SilkS")
		)
		(fp_line
			(start 2.504948 -1.616456)
			(end 2.504948 1.633728)
			(stroke
				(width 0.1524)
				(type default)
			)
			(layer "F.SilkS")
		)
		(fp_line
			(start 2.286 7.366)
			(end 2.286 1.63195)
			(stroke
				(width 0.1524)
				(type default)
			)
			(layer "F.SilkS")
		)
		(fp_line
			(start 2.286 7.366)
			(end 1.600708 7.366)
			(stroke
				(width 0.1524)
				(type default)
			)
			(layer "F.SilkS")
		)
		(fp_line
			(start 1.6002 -1.616456)
			(end 2.504948 -1.616456)
			(stroke
				(width 0.1524)
				(type default)
			)
			(layer "F.SilkS")
		)
		(fp_line
			(start -1.6002 -1.616456)
			(end -2.563114 -1.616456)
			(stroke
				(width 0.1524)
				(type default)
			)
			(layer "F.SilkS")
		)
		(fp_line
			(start -2.286 7.366)
			(end -1.60147 7.366)
			(stroke
				(width 0.1524)
				(type default)
			)
			(layer "F.SilkS")
		)
		(fp_line
			(start -2.286 7.366)
			(end -2.286 1.632712)
			(stroke
				(width 0.1524)
				(type default)
			)
			(layer "F.SilkS")
		)
		(fp_line
			(start -2.563114 1.633728)
			(end -1.6002 1.633728)
			(stroke
				(width 0.1524)
				(type default)
			)
			(layer "F.SilkS")
		)
		(fp_line
			(start -2.563114 -1.616456)
			(end -2.563114 1.633728)
			(stroke
				(width 0.1524)
				(type default)
			)
			(layer "F.SilkS")
		)
		(fp_rect
			(start -2.286 7.366)
			(end 2.286 -0.254)
			(stroke
				(width 0)
				(type default)
			)
			(fill no)
			(layer "F.CrtYd")
		)
		(fp_line
			(start 2.286 7.366)
			(end -2.286 7.366)
			(stroke
				(width 0.1)
				(type default)
			)
			(layer "F.Fab")
		)
		(fp_line
			(start 2.286 -0.254)
			(end 2.286 7.366)
			(stroke
				(width 0.1)
				(type default)
			)
			(layer "F.Fab")
		)
		(fp_line
			(start -2.286 7.366)
			(end -2.286 -0.254)
			(stroke
				(width 0.1)
				(type default)
			)
			(layer "F.Fab")
		)
		(fp_line
			(start -2.286 -0.254)
			(end 2.286 -0.254)
			(stroke
				(width 0.1)
				(type default)
			)
			(layer "F.Fab")
		)
		(pad "1" smd rect
			(at 0 0 180)
			(size 2.54 3.048)
			(layers "F.Cu" "F.Mask" "F.Paste")
			(net "PVNN_PCH_STBY")
		)
		(pad "2" smd rect
			(at 0 7.112 180)
			(size 2.54 3.048)
			(layers "F.Cu" "F.Mask" "F.Paste")
			(net "GND")
		)
	)
)
